# T6G (Grand Teton) — schematic netlist excerpt (pin names and nets, part order shuffled) for the footprints in the layout excerpt that follows; sources: Cadence DE-HDL packaged netlist, KiCad conversion of 04192023_DAF0TMB3IC0_F0TG_MB_C_brd_V02_OCP.brd

R1242  Q_RES  1K 1% CHIP  pkg 0402LF  page 258 : A = ADC128_2_A0 ; B = GND
C2171  Q_CAP  22UF 4V 20% X6S  pkg C0402  page 69 : A = PVDDCR_CPU0_P0 ; B = GND
C204  Q_CAP  1UF 4V 20% X6S  pkg 0201  page 334 : A = P1V8_CPU1_RT1_1A ; B = GND

(kicad_pcb
	(version 20260206)
	(generator "pcbnew")
	(generator_version "10.0")
	(general
		(thickness 1.6)
		(legacy_teardrops no)
	)
	(paper "A4")
	(title_block
		(title "04192023_DAF0TMB3IC0_F0TG_MB_C_brd_V02_OCP.brd")
		(comment 1 "Grand Teton / footprints 4935-4937 of 8354")
	)
	(layers
		(0 "F.Cu" signal "TOP")
		(4 "In1.Cu" signal "GND")
		(6 "In2.Cu" signal "IN1")
		(8 "In3.Cu" signal "GND1")
		(10 "In4.Cu" signal "IN2")
		(12 "In5.Cu" signal "GND2")
		(14 "In6.Cu" signal "IN3")
		(16 "In7.Cu" signal "GND3")
		(18 "In8.Cu" signal "VCC")
		(20 "In9.Cu" signal "VCC1")
		(22 "In10.Cu" signal "GND4")
		(24 "In11.Cu" signal "IN4")
		(26 "In12.Cu" signal "GND5")
		(28 "In13.Cu" signal "IN5")
		(30 "In14.Cu" signal "GND6")
		(32 "In15.Cu" signal "IN6")
		(34 "In16.Cu" signal "GND7")
		(2 "B.Cu" signal "BOTTOM")
		(9 "F.Adhes" user "F.Adhesive")
		(11 "B.Adhes" user "B.Adhesive")
		(13 "F.Paste" user "Package Geometry/Pastemask Top")
		(15 "B.Paste" user "Package Geometry/Pastemask Bottom")
		(5 "F.SilkS" user "Ref Des/Silkscreen Top")
		(7 "B.SilkS" user "Ref Des/Silkscreen Bottom")
		(1 "F.Mask" user "Board Geometry/Soldermask Top")
		(3 "B.Mask" user "Board Geometry/Soldermask Bottom")
		(17 "Dwgs.User" user "User.Drawings")
		(19 "Cmts.User" user "User.Comments")
		(21 "Eco1.User" user "User.Eco1")
		(23 "Eco2.User" user "User.Eco2")
		(25 "Edge.Cuts" user "Board Geometry/Outline")
		(27 "Margin" user)
		(31 "F.CrtYd" user "Package Geometry/Place Bound Top")
		(29 "B.CrtYd" user "Package Geometry/Place Bound Bottom")
		(35 "F.Fab" user "Ref Des/Assembly Top")
		(33 "B.Fab" user "Ref Des/Assembly Bottom")
	)
	(footprint ""
		(layer "B.Cu")
		(at 213.617302 -328.110088)
		(property "Reference" "R1242"
			(at 0 0 0)
			(layer "B.SilkS")
			(hide yes)
			(effects
				(font
					(size 1.27 1.27)
				)
				(justify mirror)
			)
		)
		(property "Value" ""
			(at 0 0 0)
			(layer "B.Fab")
			(effects
				(font
					(size 1.27 1.27)
				)
				(justify mirror)
			)
		)
		(duplicate_pad_numbers_are_jumpers no)
		(fp_line
			(start -0.7874 -0.4064)
			(end -0.7874 0.4064)
			(stroke
				(width 0.1524)
				(type default)
			)
			(layer "B.SilkS")
		)
		(fp_line
			(start -0.7874 0.4064)
			(end 0.7874 0.4064)
			(stroke
				(width 0.1524)
				(type default)
			)
			(layer "B.SilkS")
		)
		(fp_line
			(start 0.7874 -0.4064)
			(end -0.7874 -0.4064)
			(stroke
				(width 0.1524)
				(type default)
			)
			(layer "B.SilkS")
		)
		(fp_line
			(start 0.7874 0.4064)
			(end 0.7874 -0.4064)
			(stroke
				(width 0.1524)
				(type default)
			)
			(layer "B.SilkS")
		)
		(fp_line
			(start -0.67945 -0.3048)
			(end -0.67945 0.3048)
			(stroke
				(width 0.1)
				(type default)
			)
			(layer "B.Fab")
		)
		(fp_line
			(start -0.67945 0.3048)
			(end -0.120396 0.3048)
			(stroke
				(width 0.1)
				(type default)
			)
			(layer "B.Fab")
		)
		(fp_line
			(start -0.12065 -0.3048)
			(end -0.67945 -0.3048)
			(stroke
				(width 0.1)
				(type default)
			)
			(layer "B.Fab")
		)
		(fp_line
			(start -0.12065 -0.2794)
			(end -0.12065 -0.3048)
			(stroke
				(width 0.1)
				(type default)
			)
			(layer "B.Fab")
		)
		(fp_line
			(start -0.120396 0.2794)
			(end 0.12065 0.2794)
			(stroke
				(width 0.1)
				(type default)
			)
			(layer "B.Fab")
		)
		(fp_line
			(start -0.120396 0.3048)
			(end -0.120396 0.2794)
			(stroke
				(width 0.1)
				(type default)
			)
			(layer "B.Fab")
		)
		(fp_line
			(start 0.12065 -0.305054)
			(end 0.12065 -0.2794)
			(stroke
				(width 0.1)
				(type default)
			)
			(layer "B.Fab")
		)
		(fp_line
			(start 0.12065 -0.2794)
			(end -0.12065 -0.2794)
			(stroke
				(width 0.1)
				(type default)
			)
			(layer "B.Fab")
		)
		(fp_line
			(start 0.12065 0.2794)
			(end 0.12065 0.3048)
			(stroke
				(width 0.1)
				(type default)
			)
			(layer "B.Fab")
		)
		(fp_line
			(start 0.12065 0.3048)
			(end 0.67945 0.3048)
			(stroke
				(width 0.1)
				(type default)
			)
			(layer "B.Fab")
		)
		(fp_line
			(start 0.67945 -0.305054)
			(end 0.12065 -0.305054)
			(stroke
				(width 0.1)
				(type default)
			)
			(layer "B.Fab")
		)
		(fp_line
			(start 0.67945 0.3048)
			(end 0.67945 -0.305054)
			(stroke
				(width 0.1)
				(type default)
			)
			(layer "B.Fab")
		)
		(pad "1" smd circle
			(at 0.40005 0 180)
			(size 0 0)
			(layers "B.Cu" "B.Mask" "B.Paste")
			(net "ADC128_2_A0")
		)
		(pad "2" smd circle
			(at -0.40005 0 180)
			(size 0 0)
			(layers "B.Cu" "B.Mask" "B.Paste")
			(net "GND")
		)
	)
	(footprint ""
		(layer "B.Cu")
		(at 87.246206 -388.011162 -90)
		(property "Reference" "C204"
			(at 0 0 90)
			(layer "B.SilkS")
			(hide yes)
			(effects
				(font
					(size 1.27 1.27)
				)
				(justify mirror)
			)
		)
		(property "Value" ""
			(at 0 0 90)
			(layer "B.Fab")
			(effects
				(font
					(size 1.27 1.27)
				)
				(justify mirror)
			)
		)
		(duplicate_pad_numbers_are_jumpers no)
		(fp_line
			(start -0.299974 0.150114)
			(end 0.299974 0.150114)
			(stroke
				(width 0.1)
				(type default)
			)
			(layer "B.Fab")
		)
		(fp_line
			(start 0.299974 0.150114)
			(end 0.299974 -0.150114)
			(stroke
				(width 0.1)
				(type default)
			)
			(layer "B.Fab")
		)
		(fp_line
			(start -0.299974 -0.150114)
			(end -0.299974 0.150114)
			(stroke
				(width 0.1)
				(type default)
			)
			(layer "B.Fab")
		)
		(fp_line
			(start 0.299974 -0.150114)
			(end -0.299974 -0.150114)
			(stroke
				(width 0.1)
				(type default)
			)
			(layer "B.Fab")
		)
		(pad "1" smd rect
			(at 0.2667 0 90)
			(size 0.3048 0.381)
			(layers "B.Cu" "B.Mask" "B.Paste")
			(net "P1V8_CPU1_RT1_1A")
		)
		(pad "2" smd rect
			(at -0.2667 0 90)
			(size 0.3048 0.381)
			(layers "B.Cu" "B.Mask" "B.Paste")
			(net "GND")
		)
	)
	(footprint ""
		(layer "B.Cu")
		(at 361.391454 -246.44731 -60)
		(property "Reference" "C2171"
			(at 0 0 120)
			(layer "B.SilkS")
			(hide yes)
			(effects
				(font
					(size 1.27 1.27)
				)
				(justify mirror)
			)
		)
		(property "Value" ""
			(at 0 0 120)
			(layer "B.Fab")
			(effects
				(font
					(size 1.27 1.27)
				)
				(justify mirror)
			)
		)
		(duplicate_pad_numbers_are_jumpers no)
		(fp_line
			(start -0.787516 0.406438)
			(end 0.787425 0.40652)
			(stroke
				(width 0.1524)
				(type default)
			)
			(layer "B.SilkS")
		)
		(fp_line
			(start -0.787425 -0.40652)
			(end -0.787516 0.406438)
			(stroke
				(width 0.1524)
				(type default)
			)
			(layer "B.SilkS")
		)
		(fp_line
			(start 0.787425 0.40652)
			(end 0.787516 -0.406438)
			(stroke
				(width 0.1524)
				(type default)
			)
			(layer "B.SilkS")
		)
		(fp_line
			(start 0.787516 -0.406438)
			(end -0.787425 -0.40652)
			(stroke
				(width 0.1524)
				(type default)
			)
			(layer "B.SilkS")
		)
		(fp_line
			(start -0.679568 0.304811)
			(end -0.120258 0.304812)
			(stroke
				(width 0.1)
				(type default)
			)
			(layer "B.Fab")
		)
		(fp_line
			(start -0.120258 0.304812)
			(end -0.120334 0.279545)
			(stroke
				(width 0.1)
				(type default)
			)
			(layer "B.Fab")
		)
		(fp_line
			(start -0.120334 0.279545)
			(end 0.120587 0.279326)
			(stroke
				(width 0.1)
				(type default)
			)
			(layer "B.Fab")
		)
		(fp_line
			(start 0.120536 0.304813)
			(end 0.6795 0.304908)
			(stroke
				(width 0.1)
				(type default)
			)
			(layer "B.Fab")
		)
		(fp_line
			(start 0.120587 0.279326)
			(end 0.120536 0.304813)
			(stroke
				(width 0.1)
				(type default)
			)
			(layer "B.Fab")
		)
		(fp_line
			(start -0.6795 -0.304908)
			(end -0.679568 0.304811)
			(stroke
				(width 0.1)
				(type default)
			)
			(layer "B.Fab")
		)
		(fp_line
			(start 0.6795 0.304908)
			(end 0.679475 -0.305158)
			(stroke
				(width 0.1)
				(type default)
			)
			(layer "B.Fab")
		)
		(fp_line
			(start -0.120587 -0.279326)
			(end -0.120536 -0.304813)
			(stroke
				(width 0.1)
				(type default)
			)
			(layer "B.Fab")
		)
		(fp_line
			(start -0.120536 -0.304813)
			(end -0.6795 -0.304908)
			(stroke
				(width 0.1)
				(type default)
			)
			(layer "B.Fab")
		)
		(fp_line
			(start 0.120554 -0.279418)
			(end -0.120587 -0.279326)
			(stroke
				(width 0.1)
				(type default)
			)
			(layer "B.Fab")
		)
		(fp_line
			(start 0.120732 -0.305125)
			(end 0.120554 -0.279418)
			(stroke
				(width 0.1)
				(type default)
			)
			(layer "B.Fab")
		)
		(fp_line
			(start 0.679475 -0.305158)
			(end 0.120732 -0.305125)
			(stroke
				(width 0.1)
				(type default)
			)
			(layer "B.Fab")
		)
		(pad "1" smd circle
			(at 0.40005 0 120)
			(size 0 0)
			(layers "B.Cu" "B.Mask" "B.Paste")
			(net "PVDDCR_CPU0_P0")
		)
		(pad "2" smd circle
			(at -0.40005 0 120)
			(size 0 0)
			(layers "B.Cu" "B.Mask" "B.Paste")
			(net "GND")
		)
	)
)
